(kicad_pcb
	(version 20260206)
	(generator "pcbnew")
	(generator_version "10.0")
	(general
		(thickness 1.6)
		(legacy_teardrops no)
	)
	(paper "A4")
	(title_block
		(title "01162023_DA0F0TEBIF0_F0T_Expander_BD_F_brd_V02_OCP.brd")
		(comment 1 "Grand Teton / footprints 2786-2791 of 9728")
	)
	(layers
		(0 "F.Cu" signal "TOP")
		(4 "In1.Cu" signal "GND")
		(6 "In2.Cu" signal "VCC")
		(8 "In3.Cu" signal "VCC1")
		(10 "In4.Cu" signal "GND1")
		(12 "In5.Cu" signal "IN1")
		(14 "In6.Cu" signal "GND2")
		(16 "In7.Cu" signal "IN2")
		(18 "In8.Cu" signal "GND3")
		(20 "In9.Cu" signal "IN3")
		(22 "In10.Cu" signal "GND4")
		(24 "In11.Cu" signal "IN4")
		(26 "In12.Cu" signal "GND5")
		(28 "In13.Cu" signal "IN5")
		(30 "In14.Cu" signal "GND6")
		(32 "In15.Cu" signal "IN6")
		(34 "In16.Cu" signal "GND7")
		(2 "B.Cu" signal "BOTTOM")
		(9 "F.Adhes" user "F.Adhesive")
		(11 "B.Adhes" user "B.Adhesive")
		(13 "F.Paste" user "Package Geometry/Pastemask Top")
		(15 "B.Paste" user "Package Geometry/Pastemask Bottom")
		(5 "F.SilkS" user "Ref Des/Silkscreen Top")
		(7 "B.SilkS" user "Ref Des/Silkscreen Bottom")
		(1 "F.Mask" user "Board Geometry/Soldermask Top")
		(3 "B.Mask" user "Board Geometry/Soldermask Bottom")
		(17 "Dwgs.User" user "User.Drawings")
		(19 "Cmts.User" user "User.Comments")
		(21 "Eco1.User" user "User.Eco1")
		(23 "Eco2.User" user "User.Eco2")
		(25 "Edge.Cuts" user "Board Geometry/Outline")
		(27 "Margin" user)
		(31 "F.CrtYd" user "Package Geometry/Place Bound Top")
		(29 "B.CrtYd" user "Package Geometry/Place Bound Bottom")
		(35 "F.Fab" user "Ref Des/Assembly Top")
		(33 "B.Fab" user "Ref Des/Assembly Bottom")
	)
	(footprint ""
		(layer "F.Cu")
		(at 304.473864 -72.766682 90)
		(property "Reference" "PR7081"
			(at 0 0 90)
			(layer "F.SilkS")
			(hide yes)
			(effects
				(font
					(size 1.27 1.27)
				)
			)
		)
		(property "Value" ""
			(at 0 0 90)
			(layer "F.Fab")
			(effects
				(font
					(size 1.27 1.27)
				)
			)
		)
		(duplicate_pad_numbers_are_jumpers no)
		(fp_line
			(start 0.7874 -0.4064)
			(end 0.7874 0.4064)
			(stroke
				(width 0.1524)
				(type default)
			)
			(layer "F.SilkS")
		)
		(fp_line
			(start -0.7874 -0.4064)
			(end 0.7874 -0.4064)
			(stroke
				(width 0.1524)
				(type default)
			)
			(layer "F.SilkS")
		)
		(fp_line
			(start 0.7874 0.4064)
			(end -0.7874 0.4064)
			(stroke
				(width 0.1524)
				(type default)
			)
			(layer "F.SilkS")
		)
		(fp_line
			(start -0.7874 0.4064)
			(end -0.7874 -0.4064)
			(stroke
				(width 0.1524)
				(type default)
			)
			(layer "F.SilkS")
		)
		(fp_line
			(start -0.12065 -0.305054)
			(end -0.12065 -0.2794)
			(stroke
				(width 0.1)
				(type default)
			)
			(layer "F.Fab")
		)
		(fp_line
			(start -0.67945 -0.305054)
			(end -0.12065 -0.305054)
			(stroke
				(width 0.1)
				(type default)
			)
			(layer "F.Fab")
		)
		(fp_line
			(start 0.67945 -0.3048)
			(end 0.67945 0.3048)
			(stroke
				(width 0.1)
				(type default)
			)
			(layer "F.Fab")
		)
		(fp_line
			(start 0.12065 -0.3048)
			(end 0.67945 -0.3048)
			(stroke
				(width 0.1)
				(type default)
			)
			(layer "F.Fab")
		)
		(fp_line
			(start 0.12065 -0.2794)
			(end 0.12065 -0.3048)
			(stroke
				(width 0.1)
				(type default)
			)
			(layer "F.Fab")
		)
		(fp_line
			(start -0.12065 -0.2794)
			(end 0.12065 -0.2794)
			(stroke
				(width 0.1)
				(type default)
			)
			(layer "F.Fab")
		)
		(fp_line
			(start 0.120396 0.2794)
			(end -0.12065 0.2794)
			(stroke
				(width 0.1)
				(type default)
			)
			(layer "F.Fab")
		)
		(fp_line
			(start -0.12065 0.2794)
			(end -0.12065 0.3048)
			(stroke
				(width 0.1)
				(type default)
			)
			(layer "F.Fab")
		)
		(fp_line
			(start 0.67945 0.3048)
			(end 0.120396 0.3048)
			(stroke
				(width 0.1)
				(type default)
			)
			(layer "F.Fab")
		)
		(fp_line
			(start 0.120396 0.3048)
			(end 0.120396 0.2794)
			(stroke
				(width 0.1)
				(type default)
			)
			(layer "F.Fab")
		)
		(fp_line
			(start -0.12065 0.3048)
			(end -0.67945 0.3048)
			(stroke
				(width 0.1)
				(type default)
			)
			(layer "F.Fab")
		)
		(fp_line
			(start -0.67945 0.3048)
			(end -0.67945 -0.305054)
			(stroke
				(width 0.1)
				(type default)
			)
			(layer "F.Fab")
		)
		(pad "1" smd circle
			(at -0.40005 0 90)
			(size 0 0)
			(layers "F.Cu" "F.Mask" "F.Paste")
			(net "P12V_SSD10_CO_MODE")
		)
		(pad "2" smd circle
			(at 0.40005 0 90)
			(size 0 0)
			(layers "F.Cu" "F.Mask" "F.Paste")
			(net "GND")
		)
	)
	(footprint ""
		(layer "F.Cu")
		(at 171.929044 -117.5512)
		(property "Reference" "R107"
			(at 0 0 0)
			(layer "F.SilkS")
			(hide yes)
			(effects
				(font
					(size 1.27 1.27)
				)
			)
		)
		(property "Value" ""
			(at 0 0 0)
			(layer "F.Fab")
			(effects
				(font
					(size 1.27 1.27)
				)
			)
		)
		(duplicate_pad_numbers_are_jumpers no)
		(fp_line
			(start -0.7874 -0.4064)
			(end 0.7874 -0.4064)
			(stroke
				(width 0.1524)
				(type default)
			)
			(layer "F.SilkS")
		)
		(fp_line
			(start -0.7874 0.4064)
			(end -0.7874 -0.4064)
			(stroke
				(width 0.1524)
				(type default)
			)
			(layer "F.SilkS")
		)
		(fp_line
			(start 0.7874 -0.4064)
			(end 0.7874 0.4064)
			(stroke
				(width 0.1524)
				(type default)
			)
			(layer "F.SilkS")
		)
		(fp_line
			(start 0.7874 0.4064)
			(end -0.7874 0.4064)
			(stroke
				(width 0.1524)
				(type default)
			)
			(layer "F.SilkS")
		)
		(fp_line
			(start -0.67945 -0.305054)
			(end -0.12065 -0.305054)
			(stroke
				(width 0.1)
				(type default)
			)
			(layer "F.Fab")
		)
		(fp_line
			(start -0.67945 0.3048)
			(end -0.67945 -0.305054)
			(stroke
				(width 0.1)
				(type default)
			)
			(layer "F.Fab")
		)
		(fp_line
			(start -0.12065 -0.305054)
			(end -0.12065 -0.2794)
			(stroke
				(width 0.1)
				(type default)
			)
			(layer "F.Fab")
		)
		(fp_line
			(start -0.12065 -0.2794)
			(end 0.12065 -0.2794)
			(stroke
				(width 0.1)
				(type default)
			)
			(layer "F.Fab")
		)
		(fp_line
			(start -0.12065 0.2794)
			(end -0.12065 0.3048)
			(stroke
				(width 0.1)
				(type default)
			)
			(layer "F.Fab")
		)
		(fp_line
			(start -0.12065 0.3048)
			(end -0.67945 0.3048)
			(stroke
				(width 0.1)
				(type default)
			)
			(layer "F.Fab")
		)
		(fp_line
			(start 0.120396 0.2794)
			(end -0.12065 0.2794)
			(stroke
				(width 0.1)
				(type default)
			)
			(layer "F.Fab")
		)
		(fp_line
			(start 0.120396 0.3048)
			(end 0.120396 0.2794)
			(stroke
				(width 0.1)
				(type default)
			)
			(layer "F.Fab")
		)
		(fp_line
			(start 0.12065 -0.3048)
			(end 0.67945 -0.3048)
			(stroke
				(width 0.1)
				(type default)
			)
			(layer "F.Fab")
		)
		(fp_line
			(start 0.12065 -0.2794)
			(end 0.12065 -0.3048)
			(stroke
				(width 0.1)
				(type default)
			)
			(layer "F.Fab")
		)
		(fp_line
			(start 0.67945 -0.3048)
			(end 0.67945 0.3048)
			(stroke
				(width 0.1)
				(type default)
			)
			(layer "F.Fab")
		)
		(fp_line
			(start 0.67945 0.3048)
			(end 0.120396 0.3048)
			(stroke
				(width 0.1)
				(type default)
			)
			(layer "F.Fab")
		)
		(pad "1" smd circle
			(at -0.40005 0)
			(size 0 0)
			(layers "F.Cu" "F.Mask" "F.Paste")
			(net "PRSNTB1_NIC2_N")
		)
		(pad "2" smd circle
			(at 0.40005 0)
			(size 0 0)
			(layers "F.Cu" "F.Mask" "F.Paste")
			(net "P3V3_AUX")
		)
	)
	(footprint ""
		(layer "F.Cu")
		(at 134.610856 -170.599862 90)
		(property "Reference" "R1095"
			(at 0 0 90)
			(layer "F.SilkS")
			(hide yes)
			(effects
				(font
					(size 1.27 1.27)
				)
			)
		)
		(property "Value" ""
			(at 0 0 90)
			(layer "F.Fab")
			(effects
				(font
					(size 1.27 1.27)
				)
			)
		)
		(duplicate_pad_numbers_are_jumpers no)
		(fp_line
			(start 0.7874 0.4064)
			(end -0.7874 0.4064)
			(stroke
				(width 0.1524)
				(type default)
			)
			(layer "F.SilkS")
		)
		(fp_line
			(start -0.12065 -0.305054)
			(end -0.12065 -0.2794)
			(stroke
				(width 0.1)
				(type default)
			)
			(layer "F.Fab")
		)
		(fp_line
			(start -0.67945 -0.305054)
			(end -0.12065 -0.305054)
			(stroke
				(width 0.1)
				(type default)
			)
			(layer "F.Fab")
		)
		(fp_line
			(start 0.67945 -0.3048)
			(end 0.67945 0.3048)
			(stroke
				(width 0.1)
				(type default)
			)
			(layer "F.Fab")
		)
		(fp_line
			(start 0.12065 -0.3048)
			(end 0.67945 -0.3048)
			(stroke
				(width 0.1)
				(type default)
			)
			(layer "F.Fab")
		)
		(fp_line
			(start 0.12065 -0.2794)
			(end 0.12065 -0.3048)
			(stroke
				(width 0.1)
				(type default)
			)
			(layer "F.Fab")
		)
		(fp_line
			(start -0.12065 -0.2794)
			(end 0.12065 -0.2794)
			(stroke
				(width 0.1)
				(type default)
			)
			(layer "F.Fab")
		)
		(fp_line
			(start 0.120396 0.2794)
			(end -0.12065 0.2794)
			(stroke
				(width 0.1)
				(type default)
			)
			(layer "F.Fab")
		)
		(fp_line
			(start -0.12065 0.2794)
			(end -0.12065 0.3048)
			(stroke
				(width 0.1)
				(type default)
			)
			(layer "F.Fab")
		)
		(fp_line
			(start 0.67945 0.3048)
			(end 0.120396 0.3048)
			(stroke
				(width 0.1)
				(type default)
			)
			(layer "F.Fab")
		)
		(fp_line
			(start 0.120396 0.3048)
			(end 0.120396 0.2794)
			(stroke
				(width 0.1)
				(type default)
			)
			(layer "F.Fab")
		)
		(fp_line
			(start -0.12065 0.3048)
			(end -0.67945 0.3048)
			(stroke
				(width 0.1)
				(type default)
			)
			(layer "F.Fab")
		)
		(fp_line
			(start -0.67945 0.3048)
			(end -0.67945 -0.305054)
			(stroke
				(width 0.1)
				(type default)
			)
			(layer "F.Fab")
		)
		(pad "1" smd circle
			(at -0.40005 0 90)
			(size 0 0)
			(layers "F.Cu" "F.Mask" "F.Paste")
			(net "CLK_100M_DB2000QL_NIC0_R_DN")
		)
		(pad "2" smd circle
			(at 0.40005 0 90)
			(size 0 0)
			(layers "F.Cu" "F.Mask" "F.Paste")
			(net "CLK_100M_DB2000QL_NIC0_DN")
		)
	)
	(footprint ""
		(layer "F.Cu")
		(at 447.166238 -95.263716 -90)
		(property "Reference" "PC336"
			(at 0 0 270)
			(layer "F.SilkS")
			(hide yes)
			(effects
				(font
					(size 1.27 1.27)
				)
			)
		)
		(property "Value" ""
			(at 0 0 270)
			(layer "F.Fab")
			(effects
				(font
					(size 1.27 1.27)
				)
			)
		)
		(duplicate_pad_numbers_are_jumpers no)
		(fp_line
			(start -0.7874 0.4064)
			(end -0.7874 -0.4064)
			(stroke
				(width 0.1524)
				(type default)
			)
			(layer "F.SilkS")
		)
		(fp_line
			(start 0.7874 0.4064)
			(end -0.7874 0.4064)
			(stroke
				(width 0.1524)
				(type default)
			)
			(layer "F.SilkS")
		)
		(fp_line
			(start -0.7874 -0.4064)
			(end 0.7874 -0.4064)
			(stroke
				(width 0.1524)
				(type default)
			)
			(layer "F.SilkS")
		)
		(fp_line
			(start 0.7874 -0.4064)
			(end 0.7874 0.4064)
			(stroke
				(width 0.1524)
				(type default)
			)
			(layer "F.SilkS")
		)
		(fp_line
			(start -0.67945 0.3048)
			(end -0.67945 -0.305054)
			(stroke
				(width 0.1)
				(type default)
			)
			(layer "F.Fab")
		)
		(fp_line
			(start -0.12065 0.3048)
			(end -0.67945 0.3048)
			(stroke
				(width 0.1)
				(type default)
			)
			(layer "F.Fab")
		)
		(fp_line
			(start 0.120396 0.3048)
			(end 0.120396 0.2794)
			(stroke
				(width 0.1)
				(type default)
			)
			(layer "F.Fab")
		)
		(fp_line
			(start 0.67945 0.3048)
			(end 0.120396 0.3048)
			(stroke
				(width 0.1)
				(type default)
			)
			(layer "F.Fab")
		)
		(fp_line
			(start -0.12065 0.2794)
			(end -0.12065 0.3048)
			(stroke
				(width 0.1)
				(type default)
			)
			(layer "F.Fab")
		)
		(fp_line
			(start 0.120396 0.2794)
			(end -0.12065 0.2794)
			(stroke
				(width 0.1)
				(type default)
			)
			(layer "F.Fab")
		)
		(fp_line
			(start -0.12065 -0.2794)
			(end 0.12065 -0.2794)
			(stroke
				(width 0.1)
				(type default)
			)
			(layer "F.Fab")
		)
		(fp_line
			(start 0.12065 -0.2794)
			(end 0.12065 -0.3048)
			(stroke
				(width 0.1)
				(type default)
			)
			(layer "F.Fab")
		)
		(fp_line
			(start 0.12065 -0.3048)
			(end 0.67945 -0.3048)
			(stroke
				(width 0.1)
				(type default)
			)
			(layer "F.Fab")
		)
		(fp_line
			(start 0.67945 -0.3048)
			(end 0.67945 0.3048)
			(stroke
				(width 0.1)
				(type default)
			)
			(layer "F.Fab")
		)
		(fp_line
			(start -0.67945 -0.305054)
			(end -0.12065 -0.305054)
			(stroke
				(width 0.1)
				(type default)
			)
			(layer "F.Fab")
		)
		(fp_line
			(start -0.12065 -0.305054)
			(end -0.12065 -0.2794)
			(stroke
				(width 0.1)
				(type default)
			)
			(layer "F.Fab")
		)
		(pad "1" smd circle
			(at -0.40005 0 270)
			(size 0 0)
			(layers "F.Cu" "F.Mask" "F.Paste")
			(net "P5V_AUX")
		)
		(pad "2" smd circle
			(at 0.40005 0 270)
			(size 0 0)
			(layers "F.Cu" "F.Mask" "F.Paste")
			(net "GND")
		)
	)
	(footprint ""
		(layer "F.Cu")
		(at 230.660956 -86.833456 -90)
		(property "Reference" "R1008"
			(at 0 0 270)
			(layer "F.SilkS")
			(hide yes)
			(effects
				(font
					(size 1.27 1.27)
				)
			)
		)
		(property "Value" ""
			(at 0 0 270)
			(layer "F.Fab")
			(effects
				(font
					(size 1.27 1.27)
				)
			)
		)
		(duplicate_pad_numbers_are_jumpers no)
		(fp_line
			(start -0.7874 -0.4064)
			(end 0.7874 -0.4064)
			(stroke
				(width 0.1524)
				(type default)
			)
			(layer "F.SilkS")
		)
		(fp_line
			(start -0.67945 0.3048)
			(end -0.67945 -0.305054)
			(stroke
				(width 0.1)
				(type default)
			)
			(layer "F.Fab")
		)
		(fp_line
			(start -0.12065 0.3048)
			(end -0.67945 0.3048)
			(stroke
				(width 0.1)
				(type default)
			)
			(layer "F.Fab")
		)
		(fp_line
			(start 0.120396 0.3048)
			(end 0.120396 0.2794)
			(stroke
				(width 0.1)
				(type default)
			)
			(layer "F.Fab")
		)
		(fp_line
			(start 0.67945 0.3048)
			(end 0.120396 0.3048)
			(stroke
				(width 0.1)
				(type default)
			)
			(layer "F.Fab")
		)
		(fp_line
			(start -0.12065 0.2794)
			(end -0.12065 0.3048)
			(stroke
				(width 0.1)
				(type default)
			)
			(layer "F.Fab")
		)
		(fp_line
			(start 0.120396 0.2794)
			(end -0.12065 0.2794)
			(stroke
				(width 0.1)
				(type default)
			)
			(layer "F.Fab")
		)
		(fp_line
			(start -0.12065 -0.2794)
			(end 0.12065 -0.2794)
			(stroke
				(width 0.1)
				(type default)
			)
			(layer "F.Fab")
		)
		(fp_line
			(start 0.12065 -0.2794)
			(end 0.12065 -0.3048)
			(stroke
				(width 0.1)
				(type default)
			)
			(layer "F.Fab")
		)
		(fp_line
			(start 0.12065 -0.3048)
			(end 0.67945 -0.3048)
			(stroke
				(width 0.1)
				(type default)
			)
			(layer "F.Fab")
		)
		(fp_line
			(start 0.67945 -0.3048)
			(end 0.67945 0.3048)
			(stroke
				(width 0.1)
				(type default)
			)
			(layer "F.Fab")
		)
		(fp_line
			(start -0.67945 -0.305054)
			(end -0.12065 -0.305054)
			(stroke
				(width 0.1)
				(type default)
			)
			(layer "F.Fab")
		)
		(fp_line
			(start -0.12065 -0.305054)
			(end -0.12065 -0.2794)
			(stroke
				(width 0.1)
				(type default)
			)
			(layer "F.Fab")
		)
		(pad "1" smd circle
			(at -0.40005 0 270)
			(size 0 0)
			(layers "F.Cu" "F.Mask" "F.Paste")
			(net "USB2_PEX_HUB_R_DP")
		)
		(pad "2" smd circle
			(at 0.40005 0 270)
			(size 0 0)
			(layers "F.Cu" "F.Mask" "F.Paste")
			(net "USB2_PEX_HUB_DP")
		)
	)
	(footprint ""
		(layer "F.Cu")
		(at 95.105728 -238.753904)
		(property "Reference" "R5627"
			(at 0 0 0)
			(layer "F.SilkS")
			(hide yes)
			(effects
				(font
					(size 1.27 1.27)
				)
			)
		)
		(property "Value" ""
			(at 0 0 0)
			(layer "F.Fab")
			(effects
				(font
					(size 1.27 1.27)
				)
			)
		)
		(duplicate_pad_numbers_are_jumpers no)
		(fp_line
			(start -0.7874 -0.4064)
			(end 0.7874 -0.4064)
			(stroke
				(width 0.1524)
				(type default)
			)
			(layer "F.SilkS")
		)
		(fp_line
			(start -0.7874 0.4064)
			(end -0.7874 -0.4064)
			(stroke
				(width 0.1524)
				(type default)
			)
			(layer "F.SilkS")
		)
		(fp_line
			(start 0.7874 -0.4064)
			(end 0.7874 0.4064)
			(stroke
				(width 0.1524)
				(type default)
			)
			(layer "F.SilkS")
		)
		(fp_line
			(start 0.7874 0.4064)
			(end -0.7874 0.4064)
			(stroke
				(width 0.1524)
				(type default)
			)
			(layer "F.SilkS")
		)
		(fp_line
			(start -0.67945 -0.305054)
			(end -0.12065 -0.305054)
			(stroke
				(width 0.1)
				(type default)
			)
			(layer "F.Fab")
		)
		(fp_line
			(start -0.67945 0.3048)
			(end -0.67945 -0.305054)
			(stroke
				(width 0.1)
				(type default)
			)
			(layer "F.Fab")
		)
		(fp_line
			(start -0.12065 -0.305054)
			(end -0.12065 -0.2794)
			(stroke
				(width 0.1)
				(type default)
			)
			(layer "F.Fab")
		)
		(fp_line
			(start -0.12065 -0.2794)
			(end 0.12065 -0.2794)
			(stroke
				(width 0.1)
				(type default)
			)
			(layer "F.Fab")
		)
		(fp_line
			(start -0.12065 0.2794)
			(end -0.12065 0.3048)
			(stroke
				(width 0.1)
				(type default)
			)
			(layer "F.Fab")
		)
		(fp_line
			(start -0.12065 0.3048)
			(end -0.67945 0.3048)
			(stroke
				(width 0.1)
				(type default)
			)
			(layer "F.Fab")
		)
		(fp_line
			(start 0.120396 0.2794)
			(end -0.12065 0.2794)
			(stroke
				(width 0.1)
				(type default)
			)
			(layer "F.Fab")
		)
		(fp_line
			(start 0.120396 0.3048)
			(end 0.120396 0.2794)
			(stroke
				(width 0.1)
				(type default)
			)
			(layer "F.Fab")
		)
		(fp_line
			(start 0.12065 -0.3048)
			(end 0.67945 -0.3048)
			(stroke
				(width 0.1)
				(type default)
			)
			(layer "F.Fab")
		)
		(fp_line
			(start 0.12065 -0.2794)
			(end 0.12065 -0.3048)
			(stroke
				(width 0.1)
				(type default)
			)
			(layer "F.Fab")
		)
		(fp_line
			(start 0.67945 -0.3048)
			(end 0.67945 0.3048)
			(stroke
				(width 0.1)
				(type default)
			)
			(layer "F.Fab")
		)
		(fp_line
			(start 0.67945 0.3048)
			(end 0.120396 0.3048)
			(stroke
				(width 0.1)
				(type default)
			)
			(layer "F.Fab")
		)
		(pad "1" smd circle
			(at -0.40005 0)
			(size 0 0)
			(layers "F.Cu" "F.Mask" "F.Paste")
			(net "PEX_P1V8_ADC_A1")
		)
		(pad "2" smd circle
			(at 0.40005 0)
			(size 0 0)
			(layers "F.Cu" "F.Mask" "F.Paste")
			(net "SMB_PEX_P1V8_ADC_SCL")
		)
	)
)
